FILE_TYPE = CONNECTIVITY;
{Allegro Design Entry HDL 17.4-2019 S026 (4007227) 1/17/2022}
"PAGE_NUMBER" = 151;
0"NC";
1"PVDD18_S5_P0\g";
2"GND\g";
3"GND\g";
4"GND\g";
5"GND\g";
6"PVDD18_S5_P0\g";
7"PVDD18_S5_P0\g";
8"GND\g";
9"GND\g";
10"GND\g";
11"GND\g";
12"GND\g";
13"GND\g";
14"GND\g";
15"PVDD18_S5_P0\g";
16"JTAG_CPUX_TDI";
17"JTAG_CPU0_TDO";
18"PVDD18_S5_P0\g";
19"PVDD18_S5_P0\g";
20"PVDD18_S5_P0\g";
21"JTAG_CPU1_TDO";
22"JTAG_CPU0_BYPASS_R1";
23"JTAG_CPU0_BYPASS";
24"JTAG_CPU0_TDO_CPU1_TDI";
25"JTAG_CPU0_TDO_CPU1_TDI_R1";
26"JTAG_CPUX_TDO";
27"JTAG_CPUX_TDO_R";
28"CPU0_HDT_BYPASS_SEL";
29"FM_PLD_CPU0_PRSNT_HDT_N";
30"CPU1_HDT_BYPASS_SEL";
31"FM_PLD_CPU1_PRSNT_HDT_N";
32"JTAG_CPU0_TDI";
33"JTAG_CPU0_R_TDI";
34"JTAG_CPU1_R_TDI";
35"JTAG_CPU1_TDI";
36"JTAG_CPU1_BYPASS";
37"PVDD18_S5_P0\g";
%"SN74AUC2G66DCTR"
"1","(-6375,5800)","0","pure_quanta","I1";
;
LOCATION"U153"
$SEC"1"
CDS_SEC"1"
PART_TYPE"SMLF"
VALUE"SN74AUC2G66DCTR"
MATERIAL"IC"
CDS_LIB"pure_quanta"
NEEDS_NO_SIZE"TRUE"
CDS_LMAN_SYM_OUTLINE"-150,125,150,-125"
PART_NUMBER"AL2G0066C00";
"2B"
$PN"6"23;
"1B"
$PN"2"33;
"GND"
$PN"4"2;
"VCC"
$PN"8"20;
"2C"
$PN"3"29;
"2A"
$PN"5"16;
"1C"
$PN"7"28;
"1A"
$PN"1"16;
%"Q_RES"
"2","(-8200,5325)","2","pure_quanta","I10";
;
LOCATION"R1646"
$SEC"1"
CDS_SEC"1"
WATTAGE"1/16W"
MATERIAL"CHIP"
TOLERANCE"1%"
VALUE"1K"
PACK_TYPE"0402LF"
CDS_LIB"pure_quanta"
PART_NUMBER"CS21002FB06";
"A"
$PN"1"15;
"B"
$PN"2"28;
%"Q_RES"
"2","(-7600,5500)","0","pure_quanta","I11";
;
LOCATION"R1647"
$SEC"1"
CDS_SEC"1"
WATTAGE"1/16W"
VALUE"1K"
TOLERANCE"1%"
MATERIAL"CHIP"
PACK_TYPE"0402LF"
CDS_LIB"pure_quanta"
PART_NUMBER"CS21002FB06";
"A"
$PN"1"1;
"B"
$PN"2"29;
%"UNIVERSAL_POWER"
"1","(-7600,5700)","0","pure_quanta_power","I12";
;
HDL_POWER"PVDD18_S5_P0"
CDS_LIB"pure_quanta_power";
"A"1;
%"GND"
"1","(-5975,5600)","0","pure_quanta_power","I13";
;
SIZE"1B"
CDS_LIB"pure_quanta_power"
HDL_POWER"GND";
"A<SIZE-1..0>\NAC"2;
%"GND"
"1","(-5725,5925)","0","pure_quanta_power","I14";
;
SIZE"1B"
CDS_LIB"pure_quanta_power"
HDL_POWER"GND";
"A<SIZE-1..0>\NAC"3;
%"Q_CAP"
"1","(-5725,6125)","0","pure_quanta","I15";
;
LOCATION"C1519"
$SEC"1"
CDS_SEC"1"
MATERIAL"X7R"
TOLERANCE"10%"
VOLTAGE"16V"
VALUE"0.1UF"
PACK_TYPE"C0402"
CDS_LIB"pure_quanta"
PART_NUMBER"CH4103K1B08";
"B"
$PN"2"3;
"A"
$PN"1"20;
%"UNIVERSAL_POWER"
"1","(-5950,6400)","0","pure_quanta_power","I16";
;
HDL_POWER"PVDD18_S5_P0"
CDS_LIB"pure_quanta_power";
"A"20;
%"SN74AUC2G66DCTR"
"1","(-4975,4450)","0","pure_quanta","I17";
;
LOCATION"U13"
SEC"1"
MATERIAL"IC"
VALUE"SN74AUC2G66DCTR"
PART_TYPE"SMLF"
CDS_LIB"pure_quanta"
CDS_LMAN_SYM_OUTLINE"-150,125,150,-125"
NEEDS_NO_SIZE"TRUE"
SEC_TYPE""
PART_NUMBER"AL2G0066C00";
"2B"
$PN"6"25;
"1B"
$PN"2"24;
"GND"
$PN"4"11;
"VCC"
$PN"8"19;
"2C"
$PN"3"29;
"2A"
$PN"5"22;
"1C"
$PN"7"28;
"1A"
$PN"1"17;
%"GND"
"1","(-7600,4650)","0","pure_quanta_power","I19";
;
SIZE"1B"
CDS_LIB"pure_quanta_power"
HDL_POWER"GND";
"A<SIZE-1..0>\NAC"4;
%"Q_RES"
"1","(-5225,5825)","0","pure_quanta","I2";
;
LOCATION"R1648"
$SEC"1"
CDS_SEC"1"
VALUE"0"
TOLERANCE"5%"
MATERIAL"CHIP"
CDS_LIB"pure_quanta"
WATTAGE"1/16W"
PACK_TYPE"0402LF"
PART_NUMBER"CS00002JB13";
"B"
$PN"2"32;
"A"
$PN"1"33;
%"UNIVERSAL_POWER"
"1","(-4225,5050)","0","pure_quanta_power","I20";
;
HDL_POWER"PVDD18_S5_P0"
CDS_LIB"pure_quanta_power";
"A"19;
%"GND"
"1","(-4000,4575)","0","pure_quanta_power","I21";
;
SIZE"1B"
CDS_LIB"pure_quanta_power"
HDL_POWER"GND";
"A<SIZE-1..0>\NAC"5;
%"Q_CAP"
"1","(-4000,4775)","0","pure_quanta","I22";
;
LOCATION"C1521"
$SEC"1"
CDS_SEC"1"
TOLERANCE"10%"
MATERIAL"X7R"
VOLTAGE"16V"
VALUE"0.1UF"
PACK_TYPE"C0402"
CDS_LIB"pure_quanta"
PART_NUMBER"CH4103K1B08";
"B"
$PN"2"5;
"A"
$PN"1"19;
%"SN74AUC2G66DCTR"
"1","(-3125,4400)","0","pure_quanta","I23";
;
LOCATION"U14"
SEC"1"
VALUE"SN74AUC2G66DCTR"
MATERIAL"IC"
PART_TYPE"SMLF"
CDS_LIB"pure_quanta"
NEEDS_NO_SIZE"TRUE"
CDS_LMAN_SYM_OUTLINE"-150,125,150,-125"
SEC_TYPE""
PART_NUMBER"AL2G0066C00";
"2B"
$PN"6"36;
"1B"
$PN"2"34;
"GND"
$PN"4"12;
"VCC"
$PN"8"37;
"2C"
$PN"3"31;
"2A"
$PN"5"24;
"1C"
$PN"7"30;
"1A"
$PN"1"24;
%"Q_RES"
"2","(-5225,3400)","2","pure_quanta","I25";
;
LOCATION"R1649"
$SEC"1"
CDS_SEC"1"
WATTAGE"1/16W"
MATERIAL"CHIP"
TOLERANCE"1%"
VALUE"1K"
PACK_TYPE"0402LF"
CDS_LIB"pure_quanta"
PART_NUMBER"CS21002FB06";
"A"
$PN"1"7;
"B"
$PN"2"30;
%"UNIVERSAL_POWER"
"1","(-4550,3725)","0","pure_quanta_power","I26";
;
HDL_POWER"PVDD18_S5_P0"
CDS_LIB"pure_quanta_power";
"A"6;
%"Q_RES"
"2","(-4550,3525)","0","pure_quanta","I27";
;
LOCATION"R1650"
$SEC"1"
CDS_SEC"1"
WATTAGE"1/16W"
MATERIAL"CHIP"
TOLERANCE"1%"
VALUE"1K"
PACK_TYPE"0402LF"
CDS_LIB"pure_quanta"
PART_NUMBER"CS21002FB06";
"A"
$PN"1"6;
"B"
$PN"2"31;
%"UNIVERSAL_POWER"
"1","(-5225,3650)","0","pure_quanta_power","I28";
;
HDL_POWER"PVDD18_S5_P0"
CDS_LIB"pure_quanta_power";
"A"7;
%"GND"
"1","(-4550,2725)","0","pure_quanta_power","I29";
;
SIZE"1B"
CDS_LIB"pure_quanta_power"
HDL_POWER"GND";
"A<SIZE-1..0>\NAC"8;
%"GND"
"1","(-4900,5325)","0","pure_quanta_power","I3";
;
CDS_LIB"pure_quanta_power"
SIZE"1B"
HDL_POWER"GND";
"A<SIZE-1..0>\NAC"9;
%"SN74AUC2G66DCTR"
"1","(-1850,3400)","0","pure_quanta","I31";
;
LOCATION"U154"
$SEC"1"
CDS_SEC"1"
VALUE"SN74AUC2G66DCTR"
MATERIAL"IC"
PART_TYPE"SMLF"
CDS_LIB"pure_quanta"
CDS_LMAN_SYM_OUTLINE"-150,125,150,-125"
NEEDS_NO_SIZE"TRUE"
PART_NUMBER"AL2G0066C00";
"2B"
$PN"6"27;
"1B"
$PN"2"27;
"GND"
$PN"4"13;
"VCC"
$PN"8"18;
"2C"
$PN"3"31;
"2A"
$PN"5"36;
"1C"
$PN"7"30;
"1A"
$PN"1"21;
%"Q_RES"
"1","(-1975,4425)","0","pure_quanta","I34";
;
LOCATION"R1651"
$SEC"1"
CDS_SEC"1"
MATERIAL"CHIP"
VALUE"0"
TOLERANCE"5%"
CDS_LIB"pure_quanta"
WATTAGE"1/16W"
PACK_TYPE"0402LF"
PART_NUMBER"CS00002JB13";
"B"
$PN"2"35;
"A"
$PN"1"34;
%"UNIVERSAL_POWER"
"1","(-2375,5000)","0","pure_quanta_power","I35";
;
HDL_POWER"PVDD18_S5_P0"
CDS_LIB"pure_quanta_power";
"A"37;
%"Q_CAP"
"1","(-2150,4725)","0","pure_quanta","I36";
;
LOCATION"C1522"
$SEC"1"
CDS_SEC"1"
PACK_TYPE"C0402"
VOLTAGE"16V"
VALUE"0.1UF"
MATERIAL"X7R"
TOLERANCE"10%"
CDS_LIB"pure_quanta"
PART_NUMBER"CH4103K1B08";
"B"
$PN"2"10;
"A"
$PN"1"37;
%"GND"
"1","(-2150,4525)","0","pure_quanta_power","I37";
;
CDS_LIB"pure_quanta_power"
SIZE"1B"
HDL_POWER"GND";
"A<SIZE-1..0>\NAC"10;
%"GND"
"1","(-4575,4250)","0","pure_quanta_power","I38";
;
SIZE"1B"
CDS_LIB"pure_quanta_power"
HDL_POWER"GND";
"A<SIZE-1..0>\NAC"11;
%"GND"
"1","(-2725,4200)","0","pure_quanta_power","I39";
;
SIZE"1B"
CDS_LIB"pure_quanta_power"
HDL_POWER"GND";
"A<SIZE-1..0>\NAC"12;
%"Q_CAP"
"1","(-4900,5625)","0","pure_quanta","I4";
;
LOCATION"C1520"
$SEC"1"
CDS_SEC"1"
VALUE"0.01UF"
VOLTAGE"50V"
TOLERANCE"10%"
PACK_TYPE"C0402"
MATERIAL"EMPTY"
CDS_LIB"pure_quanta"
PART_NUMBER"CH31006KB18";
"B"
$PN"2"9;
"A"
$PN"1"32;
%"GND"
"1","(-1450,3200)","0","pure_quanta_power","I40";
;
CDS_LIB"pure_quanta_power"
SIZE"1B"
HDL_POWER"GND";
"A<SIZE-1..0>\NAC"13;
%"Q_CAP"
"1","(-1000,3750)","0","pure_quanta","I42";
;
LOCATION"C1523"
$SEC"1"
CDS_SEC"1"
PACK_TYPE"C0402"
VOLTAGE"16V"
VALUE"0.1UF"
TOLERANCE"10%"
MATERIAL"X7R"
CDS_LIB"pure_quanta"
PART_NUMBER"CH4103K1B08";
"B"
$PN"2"14;
"A"
$PN"1"18;
%"GND"
"1","(-1000,3550)","0","pure_quanta_power","I43";
;
SIZE"1B"
CDS_LIB"pure_quanta_power"
HDL_POWER"GND";
"A<SIZE-1..0>\NAC"14;
%"UNIVERSAL_POWER"
"1","(-1225,4025)","0","pure_quanta_power","I44";
;
HDL_POWER"PVDD18_S5_P0"
CDS_LIB"pure_quanta_power";
"A"18;
%"MOSFET_N"
"1","(-7650,5075)","0","pure_quanta","I45";
;
LOCATION"Q63"
$SEC"1"
CDS_SEC"1"
MATERIAL"IC"
VALUE"BSS138K"
PART_TYPE"SMLF"
PACK_TYPE"SMLF"
CDS_LIB"pure_quanta"
CDS_LMAN_SYM_OUTLINE"-50,50,100,-150"
MANUF_PN"BSS138K"
PART_NUMBER"BAM138K0000";
"GATE"
$PN"G"28;
"SOURCE"
$PN"S"4;
"DRAIN"
$PN"D"29;
%"MOSFET_N"
"1","(-4600,3150)","0","pure_quanta","I46";
;
LOCATION"Q64"
$SEC"1"
CDS_SEC"1"
VALUE"BSS138K"
MATERIAL"IC"
PART_TYPE"SMLF"
PACK_TYPE"SMLF"
CDS_LMAN_SYM_OUTLINE"-50,50,100,-150"
CDS_LIB"pure_quanta"
MANUF_PN"BSS138K"
PART_NUMBER"BAM138K0000";
"GATE"
$PN"G"30;
"SOURCE"
$PN"S"8;
"DRAIN"
$PN"D"31;
%"Q_RES"
"1","(-6050,4950)","0","pure_quanta","I48";
;
LOCATION"R6104"
$SEC"1"
CDS_SEC"1"
VALUE"0"
CDS_LIB"pure_quanta"
BOM_COST"MEM"
WATTAGE"1/16W"
MATERIAL"CHIP"
TOLERANCE"5%"
PACK_TYPE"0402LF"
PART_NUMBER"CS00002JB13";
"B"
$PN"2"22;
"A"
$PN"1"23;
%"Q_RES"
"1","(-4225,4425)","0","pure_quanta","I49";
;
LOCATION"R6105"
$SEC"1"
CDS_SEC"1"
VALUE"0"
PACK_TYPE"0402LF"
TOLERANCE"5%"
MATERIAL"CHIP"
WATTAGE"1/16W"
BOM_COST"MEM"
CDS_LIB"pure_quanta"
PART_NUMBER"CS00002JB13";
"B"
$PN"2"24;
"A"
$PN"1"25;
%"Q_RES"
"1","(-950,3425)","0","pure_quanta","I50";
;
LOCATION"R6110"
$SEC"1"
CDS_SEC"1"
MATERIAL"CHIP"
VALUE"0"
CDS_LIB"pure_quanta"
PACK_TYPE"0402LF"
TOLERANCE"5%"
WATTAGE"1/16W"
PART_NUMBER"CS00002JB13";
"B"
$PN"2"26;
"A"
$PN"1"27;
%"UNIVERSAL_POWER"
"1","(-8200,5575)","0","pure_quanta_power","I9";
;
HDL_POWER"PVDD18_S5_P0"
CDS_LIB"pure_quanta_power";
"A"15;
END.
